(kicad_pcb
	(version 20260206)
	(generator "pcbnew")
	(generator_version "10.0")
	(general
		(thickness 1.6)
		(legacy_teardrops no)
	)
	(paper "A4")
	(title_block
		(title "Wiwynn_Tioga_Pass_MB.brd")
		(comment 1 "Tioga Pass / footprint 752 of 4770 (EU4D2), pads 1-42 of 65")
	)
	(layers
		(0 "F.Cu" signal "TOP")
		(4 "In1.Cu" signal "L2GND")
		(6 "In2.Cu" signal "L3")
		(8 "In3.Cu" signal "L4GND")
		(10 "In4.Cu" signal "L5")
		(12 "In5.Cu" signal "L6GND")
		(14 "In6.Cu" signal "L7VCC")
		(16 "In7.Cu" signal "L8VCC")
		(18 "In8.Cu" signal "L9GND")
		(20 "In9.Cu" signal "L10")
		(22 "In10.Cu" signal "L11GND")
		(24 "In11.Cu" signal "L12")
		(26 "In12.Cu" signal "L13GND")
		(2 "B.Cu" signal "BOTTOM")
		(9 "F.Adhes" user "F.Adhesive")
		(11 "B.Adhes" user "B.Adhesive")
		(13 "F.Paste" user "Package Geometry/Pastemask Top")
		(15 "B.Paste" user "Package Geometry/Pastemask Bottom")
		(5 "F.SilkS" user "Ref Des/Silkscreen Top")
		(7 "B.SilkS" user "Ref Des/Silkscreen Bottom")
		(1 "F.Mask" user "Board Geometry/Soldermask Top")
		(3 "B.Mask" user "Board Geometry/Soldermask Bottom")
		(17 "Dwgs.User" user "User.Drawings")
		(19 "Cmts.User" user "User.Comments")
		(21 "Eco1.User" user "User.Eco1")
		(23 "Eco2.User" user "User.Eco2")
		(25 "Edge.Cuts" user "Board Geometry/Outline")
		(27 "Margin" user)
		(31 "F.CrtYd" user "Package Geometry/Place Bound Top")
		(29 "B.CrtYd" user "Package Geometry/Place Bound Bottom")
		(35 "F.Fab" user "Ref Des/Assembly Top")
		(33 "B.Fab" user "Ref Des/Assembly Bottom")
	)
	(footprint ""
		(layer "F.Cu")
		(at 169.422826 -80.961992 90)
		(property "Reference" "EU4D2"
			(at -8.471662 1.773174 0)
			(unlocked yes)
			(layer "F.SilkS")
			(effects
				(font
					(size 0.7874 0.5842)
					(thickness 0.1524)
				)
				(justify left)
			)
		)
		(property "Value" ""
			(at 0 0 90)
			(layer "F.Fab")
			(effects
				(font
					(size 1.27 1.27)
				)
			)
		)
		(duplicate_pad_numbers_are_jumpers no)
		(pad "1" smd custom
			(at -4.3688 -3.750818 90)
			(size 0.0762 0.0762)
			(layers "F.Cu" "F.Mask" "F.Paste")
			(net "P3V3_DB1200_A")
			(options
				(clearance outline)
				(anchor circle)
			)
			(primitives
				(gr_poly
					(pts
						(xy -0.381 -0.1524)
						(arc
							(start 0.2286 -0.1524)
							(mid 0.381 0)
							(end 0.2286 0.1524)
						)
						(xy -0.381 0.1524)
					)
					(width 0)
					(fill yes)
				)
			)
		)
		(pad "2" smd custom
			(at -4.3688 -3.250692 90)
			(size 0.0762 0.0762)
			(layers "F.Cu" "F.Mask" "F.Paste")
			(net "GND")
			(options
				(clearance outline)
				(anchor circle)
			)
			(primitives
				(gr_poly
					(pts
						(xy -0.381 -0.1524)
						(arc
							(start 0.2286 -0.1524)
							(mid 0.381 0)
							(end 0.2286 0.1524)
						)
						(xy -0.381 0.1524)
					)
					(width 0)
					(fill yes)
				)
			)
		)
		(pad "3" smd custom
			(at -4.3688 -2.750566 90)
			(size 0.0762 0.0762)
			(layers "F.Cu" "F.Mask" "F.Paste")
			(net "Net_341")
			(options
				(clearance outline)
				(anchor circle)
			)
			(primitives
				(gr_poly
					(pts
						(xy -0.381 -0.1524)
						(arc
							(start 0.2286 -0.1524)
							(mid 0.381 0)
							(end 0.2286 0.1524)
						)
						(xy -0.381 0.1524)
					)
					(width 0)
					(fill yes)
				)
			)
		)
		(pad "4" smd custom
			(at -4.3688 -2.25044 90)
			(size 0.0762 0.0762)
			(layers "F.Cu" "F.Mask" "F.Paste")
			(net "FM_100M_N")
			(options
				(clearance outline)
				(anchor circle)
			)
			(primitives
				(gr_poly
					(pts
						(xy -0.381 -0.1524)
						(arc
							(start 0.2286 -0.1524)
							(mid 0.381 0)
							(end 0.2286 0.1524)
						)
						(xy -0.381 0.1524)
					)
					(width 0)
					(fill yes)
				)
			)
		)
		(pad "5" smd custom
			(at -4.3688 -1.750314 90)
			(size 0.0762 0.0762)
			(layers "F.Cu" "F.Mask" "F.Paste")
			(net "FM_HBW_BYPASS_LOWBW_N")
			(options
				(clearance outline)
				(anchor circle)
			)
			(primitives
				(gr_poly
					(pts
						(xy -0.381 -0.1524)
						(arc
							(start 0.2286 -0.1524)
							(mid 0.381 0)
							(end 0.2286 0.1524)
						)
						(xy -0.381 0.1524)
					)
					(width 0)
					(fill yes)
				)
			)
		)
		(pad "6" smd custom
			(at -4.3688 -1.250188 90)
			(size 0.0762 0.0762)
			(layers "F.Cu" "F.Mask" "F.Paste")
			(net "FM_DB1200_PWRGD_R")
			(options
				(clearance outline)
				(anchor circle)
			)
			(primitives
				(gr_poly
					(pts
						(xy -0.381 -0.1524)
						(arc
							(start 0.2286 -0.1524)
							(mid 0.381 0)
							(end 0.2286 0.1524)
						)
						(xy -0.381 0.1524)
					)
					(width 0)
					(fill yes)
				)
			)
		)
		(pad "7" smd custom
			(at -4.3688 -0.750062 90)
			(size 0.0762 0.0762)
			(layers "F.Cu" "F.Mask" "F.Paste")
			(net "GND")
			(options
				(clearance outline)
				(anchor circle)
			)
			(primitives
				(gr_poly
					(pts
						(xy -0.381 -0.1524)
						(arc
							(start 0.2286 -0.1524)
							(mid 0.381 0)
							(end 0.2286 0.1524)
						)
						(xy -0.381 0.1524)
					)
					(width 0)
					(fill yes)
				)
			)
		)
		(pad "8" smd custom
			(at -4.3688 -0.249936 90)
			(size 0.0762 0.0762)
			(layers "F.Cu" "F.Mask" "F.Paste")
			(net "P3V3_DB1200_R")
			(options
				(clearance outline)
				(anchor circle)
			)
			(primitives
				(gr_poly
					(pts
						(xy -0.381 -0.1524)
						(arc
							(start 0.2286 -0.1524)
							(mid 0.381 0)
							(end 0.2286 0.1524)
						)
						(xy -0.381 0.1524)
					)
					(width 0)
					(fill yes)
				)
			)
		)
		(pad "9" smd custom
			(at -4.3688 0.25019 90)
			(size 0.0762 0.0762)
			(layers "F.Cu" "F.Mask" "F.Paste")
			(net "CLK_100M_DB1200_DP")
			(options
				(clearance outline)
				(anchor circle)
			)
			(primitives
				(gr_poly
					(pts
						(xy -0.381 -0.1524)
						(arc
							(start 0.2286 -0.1524)
							(mid 0.381 0)
							(end 0.2286 0.1524)
						)
						(xy -0.381 0.1524)
					)
					(width 0)
					(fill yes)
				)
			)
		)
		(pad "10" smd custom
			(at -4.3688 0.750316 90)
			(size 0.0762 0.0762)
			(layers "F.Cu" "F.Mask" "F.Paste")
			(net "CLK_100M_DB1200_DN")
			(options
				(clearance outline)
				(anchor circle)
			)
			(primitives
				(gr_poly
					(pts
						(xy -0.381 -0.1524)
						(arc
							(start 0.2286 -0.1524)
							(mid 0.381 0)
							(end 0.2286 0.1524)
						)
						(xy -0.381 0.1524)
					)
					(width 0)
					(fill yes)
				)
			)
		)
		(pad "11" smd custom
			(at -4.3688 1.250442 90)
			(size 0.0762 0.0762)
			(layers "F.Cu" "F.Mask" "F.Paste")
			(net "FM_DB1200_SMB_SA0")
			(options
				(clearance outline)
				(anchor circle)
			)
			(primitives
				(gr_poly
					(pts
						(xy -0.381 -0.1524)
						(arc
							(start 0.2286 -0.1524)
							(mid 0.381 0)
							(end 0.2286 0.1524)
						)
						(xy -0.381 0.1524)
					)
					(width 0)
					(fill yes)
				)
			)
		)
		(pad "12" smd custom
			(at -4.3688 1.750568 90)
			(size 0.0762 0.0762)
			(layers "F.Cu" "F.Mask" "F.Paste")
			(net "SMB_HOST_STBY_LVC3_SDA_R2")
			(options
				(clearance outline)
				(anchor circle)
			)
			(primitives
				(gr_poly
					(pts
						(xy -0.381 -0.1524)
						(arc
							(start 0.2286 -0.1524)
							(mid 0.381 0)
							(end 0.2286 0.1524)
						)
						(xy -0.381 0.1524)
					)
					(width 0)
					(fill yes)
				)
			)
		)
		(pad "13" smd custom
			(at -4.3688 2.250694 90)
			(size 0.0762 0.0762)
			(layers "F.Cu" "F.Mask" "F.Paste")
			(net "SMB_HOST_STBY_LVC3_SCL_R2")
			(options
				(clearance outline)
				(anchor circle)
			)
			(primitives
				(gr_poly
					(pts
						(xy -0.381 -0.1524)
						(arc
							(start 0.2286 -0.1524)
							(mid 0.381 0)
							(end 0.2286 0.1524)
						)
						(xy -0.381 0.1524)
					)
					(width 0)
					(fill yes)
				)
			)
		)
		(pad "14" smd custom
			(at -4.3688 2.75082 90)
			(size 0.0762 0.0762)
			(layers "F.Cu" "F.Mask" "F.Paste")
			(net "FM_DB1200_SMB_SA1")
			(options
				(clearance outline)
				(anchor circle)
			)
			(primitives
				(gr_poly
					(pts
						(xy -0.381 -0.1524)
						(arc
							(start 0.2286 -0.1524)
							(mid 0.381 0)
							(end 0.2286 0.1524)
						)
						(xy -0.381 0.1524)
					)
					(width 0)
					(fill yes)
				)
			)
		)
		(pad "15" smd custom
			(at -4.3688 3.250946 90)
			(size 0.0762 0.0762)
			(layers "F.Cu" "F.Mask" "F.Paste")
			(net "Net_342")
			(options
				(clearance outline)
				(anchor circle)
			)
			(primitives
				(gr_poly
					(pts
						(xy -0.381 -0.1524)
						(arc
							(start 0.2286 -0.1524)
							(mid 0.381 0)
							(end 0.2286 0.1524)
						)
						(xy -0.381 0.1524)
					)
					(width 0)
					(fill yes)
				)
			)
		)
		(pad "16" smd custom
			(at -4.3688 3.751072 90)
			(size 0.0762 0.0762)
			(layers "F.Cu" "F.Mask" "F.Paste")
			(net "Net_343")
			(options
				(clearance outline)
				(anchor circle)
			)
			(primitives
				(gr_poly
					(pts
						(xy -0.381 -0.1524)
						(arc
							(start 0.2286 -0.1524)
							(mid 0.381 0)
							(end 0.2286 0.1524)
						)
						(xy -0.381 0.1524)
					)
					(width 0)
					(fill yes)
				)
			)
		)
		(pad "17" smd custom
			(at -3.750818 4.3688 90)
			(size 0.0762 0.0762)
			(layers "F.Cu" "F.Mask" "F.Paste")
			(net "CLK_100M_CPU0_BCLK0_R_DP")
			(options
				(clearance outline)
				(anchor circle)
			)
			(primitives
				(gr_poly
					(pts
						(xy -0.1524 0.381)
						(arc
							(start -0.1524 -0.2286)
							(mid 0 -0.381)
							(end 0.1524 -0.2286)
						)
						(xy 0.1524 0.381)
					)
					(width 0)
					(fill yes)
				)
			)
		)
		(pad "18" smd custom
			(at -3.250692 4.3688 90)
			(size 0.0762 0.0762)
			(layers "F.Cu" "F.Mask" "F.Paste")
			(net "CLK_100M_CPU0_BCLK0_R_DN")
			(options
				(clearance outline)
				(anchor circle)
			)
			(primitives
				(gr_poly
					(pts
						(xy -0.1524 0.381)
						(arc
							(start -0.1524 -0.2286)
							(mid 0 -0.381)
							(end 0.1524 -0.2286)
						)
						(xy 0.1524 0.381)
					)
					(width 0)
					(fill yes)
				)
			)
		)
		(pad "19" smd custom
			(at -2.750566 4.3688 90)
			(size 0.0762 0.0762)
			(layers "F.Cu" "F.Mask" "F.Paste")
			(net "FM_DB1200ZL_BCLKS_EN_N")
			(options
				(clearance outline)
				(anchor circle)
			)
			(primitives
				(gr_poly
					(pts
						(xy -0.1524 0.381)
						(arc
							(start -0.1524 -0.2286)
							(mid 0 -0.381)
							(end 0.1524 -0.2286)
						)
						(xy 0.1524 0.381)
					)
					(width 0)
					(fill yes)
				)
			)
		)
		(pad "20" smd custom
			(at -2.25044 4.3688 90)
			(size 0.0762 0.0762)
			(layers "F.Cu" "F.Mask" "F.Paste")
			(net "FM_DB1200ZL_BCLKS_EN_N")
			(options
				(clearance outline)
				(anchor circle)
			)
			(primitives
				(gr_poly
					(pts
						(xy -0.1524 0.381)
						(arc
							(start -0.1524 -0.2286)
							(mid 0 -0.381)
							(end 0.1524 -0.2286)
						)
						(xy 0.1524 0.381)
					)
					(width 0)
					(fill yes)
				)
			)
		)
		(pad "21" smd custom
			(at -1.750314 4.3688 90)
			(size 0.0762 0.0762)
			(layers "F.Cu" "F.Mask" "F.Paste")
			(net "CLK_100M_CPU0_BCLK1_R_DP")
			(options
				(clearance outline)
				(anchor circle)
			)
			(primitives
				(gr_poly
					(pts
						(xy -0.1524 0.381)
						(arc
							(start -0.1524 -0.2286)
							(mid 0 -0.381)
							(end 0.1524 -0.2286)
						)
						(xy 0.1524 0.381)
					)
					(width 0)
					(fill yes)
				)
			)
		)
		(pad "22" smd custom
			(at -1.250188 4.3688 90)
			(size 0.0762 0.0762)
			(layers "F.Cu" "F.Mask" "F.Paste")
			(net "CLK_100M_CPU0_BCLK1_R_DN")
			(options
				(clearance outline)
				(anchor circle)
			)
			(primitives
				(gr_poly
					(pts
						(xy -0.1524 0.381)
						(arc
							(start -0.1524 -0.2286)
							(mid 0 -0.381)
							(end 0.1524 -0.2286)
						)
						(xy 0.1524 0.381)
					)
					(width 0)
					(fill yes)
				)
			)
		)
		(pad "23" smd custom
			(at -0.750062 4.3688 90)
			(size 0.0762 0.0762)
			(layers "F.Cu" "F.Mask" "F.Paste")
			(net "GND")
			(options
				(clearance outline)
				(anchor circle)
			)
			(primitives
				(gr_poly
					(pts
						(xy -0.1524 0.381)
						(arc
							(start -0.1524 -0.2286)
							(mid 0 -0.381)
							(end 0.1524 -0.2286)
						)
						(xy 0.1524 0.381)
					)
					(width 0)
					(fill yes)
				)
			)
		)
		(pad "24" smd custom
			(at -0.249936 4.3688 90)
			(size 0.0762 0.0762)
			(layers "F.Cu" "F.Mask" "F.Paste")
			(net "P3V3_DB1200")
			(options
				(clearance outline)
				(anchor circle)
			)
			(primitives
				(gr_poly
					(pts
						(xy -0.1524 0.381)
						(arc
							(start -0.1524 -0.2286)
							(mid 0 -0.381)
							(end 0.1524 -0.2286)
						)
						(xy 0.1524 0.381)
					)
					(width 0)
					(fill yes)
				)
			)
		)
		(pad "25" smd custom
			(at 0.25019 4.3688 90)
			(size 0.0762 0.0762)
			(layers "F.Cu" "F.Mask" "F.Paste")
			(net "P3V3_DB1200")
			(options
				(clearance outline)
				(anchor circle)
			)
			(primitives
				(gr_poly
					(pts
						(xy -0.1524 0.381)
						(arc
							(start -0.1524 -0.2286)
							(mid 0 -0.381)
							(end 0.1524 -0.2286)
						)
						(xy 0.1524 0.381)
					)
					(width 0)
					(fill yes)
				)
			)
		)
		(pad "26" smd custom
			(at 0.750316 4.3688 90)
			(size 0.0762 0.0762)
			(layers "F.Cu" "F.Mask" "F.Paste")
			(net "CLK_100M_CPU0_BCLK2_R_DP")
			(options
				(clearance outline)
				(anchor circle)
			)
			(primitives
				(gr_poly
					(pts
						(xy -0.1524 0.381)
						(arc
							(start -0.1524 -0.2286)
							(mid 0 -0.381)
							(end 0.1524 -0.2286)
						)
						(xy 0.1524 0.381)
					)
					(width 0)
					(fill yes)
				)
			)
		)
		(pad "27" smd custom
			(at 1.250442 4.3688 90)
			(size 0.0762 0.0762)
			(layers "F.Cu" "F.Mask" "F.Paste")
			(net "CLK_100M_CPU0_BCLK2_R_DN")
			(options
				(clearance outline)
				(anchor circle)
			)
			(primitives
				(gr_poly
					(pts
						(xy -0.1524 0.381)
						(arc
							(start -0.1524 -0.2286)
							(mid 0 -0.381)
							(end 0.1524 -0.2286)
						)
						(xy 0.1524 0.381)
					)
					(width 0)
					(fill yes)
				)
			)
		)
		(pad "28" smd custom
			(at 1.750568 4.3688 90)
			(size 0.0762 0.0762)
			(layers "F.Cu" "F.Mask" "F.Paste")
			(net "FM_DB1200ZL_BCLKS_EN_N")
			(options
				(clearance outline)
				(anchor circle)
			)
			(primitives
				(gr_poly
					(pts
						(xy -0.1524 0.381)
						(arc
							(start -0.1524 -0.2286)
							(mid 0 -0.381)
							(end 0.1524 -0.2286)
						)
						(xy 0.1524 0.381)
					)
					(width 0)
					(fill yes)
				)
			)
		)
		(pad "29" smd custom
			(at 2.250694 4.3688 90)
			(size 0.0762 0.0762)
			(layers "F.Cu" "F.Mask" "F.Paste")
			(net "FM_CPU0_MCP_CLK_EN_N")
			(options
				(clearance outline)
				(anchor circle)
			)
			(primitives
				(gr_poly
					(pts
						(xy -0.1524 0.381)
						(arc
							(start -0.1524 -0.2286)
							(mid 0 -0.381)
							(end 0.1524 -0.2286)
						)
						(xy 0.1524 0.381)
					)
					(width 0)
					(fill yes)
				)
			)
		)
		(pad "30" smd custom
			(at 2.75082 4.3688 90)
			(size 0.0762 0.0762)
			(layers "F.Cu" "F.Mask" "F.Paste")
			(net "CLK_100M_CPU0_PE_REFCLK_R_DP")
			(options
				(clearance outline)
				(anchor circle)
			)
			(primitives
				(gr_poly
					(pts
						(xy -0.1524 0.381)
						(arc
							(start -0.1524 -0.2286)
							(mid 0 -0.381)
							(end 0.1524 -0.2286)
						)
						(xy 0.1524 0.381)
					)
					(width 0)
					(fill yes)
				)
			)
		)
		(pad "31" smd custom
			(at 3.250946 4.3688 90)
			(size 0.0762 0.0762)
			(layers "F.Cu" "F.Mask" "F.Paste")
			(net "CLK_100M_CPU0_PE_REFCLK_R_DN")
			(options
				(clearance outline)
				(anchor circle)
			)
			(primitives
				(gr_poly
					(pts
						(xy -0.1524 0.381)
						(arc
							(start -0.1524 -0.2286)
							(mid 0 -0.381)
							(end 0.1524 -0.2286)
						)
						(xy 0.1524 0.381)
					)
					(width 0)
					(fill yes)
				)
			)
		)
		(pad "32" smd custom
			(at 3.751072 4.3688 90)
			(size 0.0762 0.0762)
			(layers "F.Cu" "F.Mask" "F.Paste")
			(net "P3V3_DB1200")
			(options
				(clearance outline)
				(anchor circle)
			)
			(primitives
				(gr_poly
					(pts
						(xy -0.1524 0.381)
						(arc
							(start -0.1524 -0.2286)
							(mid 0 -0.381)
							(end 0.1524 -0.2286)
						)
						(xy 0.1524 0.381)
					)
					(width 0)
					(fill yes)
				)
			)
		)
		(pad "33" smd custom
			(at 4.3688 3.751072 90)
			(size 0.0762 0.0762)
			(layers "F.Cu" "F.Mask" "F.Paste")
			(net "GND")
			(options
				(clearance outline)
				(anchor circle)
			)
			(primitives
				(gr_poly
					(pts
						(xy 0.381 0.1524)
						(arc
							(start -0.2286 0.1524)
							(mid -0.381 0)
							(end -0.2286 -0.1524)
						)
						(xy 0.381 -0.1524)
					)
					(width 0)
					(fill yes)
				)
			)
		)
		(pad "34" smd custom
			(at 4.3688 3.250946 90)
			(size 0.0762 0.0762)
			(layers "F.Cu" "F.Mask" "F.Paste")
			(net "CLK_100M_CPU0_RC_REFCLK0_R_DP")
			(options
				(clearance outline)
				(anchor circle)
			)
			(primitives
				(gr_poly
					(pts
						(xy 0.381 0.1524)
						(arc
							(start -0.2286 0.1524)
							(mid -0.381 0)
							(end -0.2286 -0.1524)
						)
						(xy 0.381 -0.1524)
					)
					(width 0)
					(fill yes)
				)
			)
		)
		(pad "35" smd custom
			(at 4.3688 2.75082 90)
			(size 0.0762 0.0762)
			(layers "F.Cu" "F.Mask" "F.Paste")
			(net "CLK_100M_CPU0_RC_REFCLK0_R_DN")
			(options
				(clearance outline)
				(anchor circle)
			)
			(primitives
				(gr_poly
					(pts
						(xy 0.381 0.1524)
						(arc
							(start -0.2286 0.1524)
							(mid -0.381 0)
							(end -0.2286 -0.1524)
						)
						(xy 0.381 -0.1524)
					)
					(width 0)
					(fill yes)
				)
			)
		)
		(pad "36" smd custom
			(at 4.3688 2.250694 90)
			(size 0.0762 0.0762)
			(layers "F.Cu" "F.Mask" "F.Paste")
			(net "FM_CPU0_MCP_CLK_EN_N")
			(options
				(clearance outline)
				(anchor circle)
			)
			(primitives
				(gr_poly
					(pts
						(xy 0.381 0.1524)
						(arc
							(start -0.2286 0.1524)
							(mid -0.381 0)
							(end -0.2286 -0.1524)
						)
						(xy 0.381 -0.1524)
					)
					(width 0)
					(fill yes)
				)
			)
		)
		(pad "37" smd custom
			(at 4.3688 1.750568 90)
			(size 0.0762 0.0762)
			(layers "F.Cu" "F.Mask" "F.Paste")
			(net "FM_CPU0_MCP_CLK_EN_N")
			(options
				(clearance outline)
				(anchor circle)
			)
			(primitives
				(gr_poly
					(pts
						(xy 0.381 0.1524)
						(arc
							(start -0.2286 0.1524)
							(mid -0.381 0)
							(end -0.2286 -0.1524)
						)
						(xy 0.381 -0.1524)
					)
					(width 0)
					(fill yes)
				)
			)
		)
		(pad "38" smd custom
			(at 4.3688 1.250442 90)
			(size 0.0762 0.0762)
			(layers "F.Cu" "F.Mask" "F.Paste")
			(net "CLK_100M_CPU0_RC_REFCLK1_R_DP")
			(options
				(clearance outline)
				(anchor circle)
			)
			(primitives
				(gr_poly
					(pts
						(xy 0.381 0.1524)
						(arc
							(start -0.2286 0.1524)
							(mid -0.381 0)
							(end -0.2286 -0.1524)
						)
						(xy 0.381 -0.1524)
					)
					(width 0)
					(fill yes)
				)
			)
		)
		(pad "39" smd custom
			(at 4.3688 0.750316 90)
			(size 0.0762 0.0762)
			(layers "F.Cu" "F.Mask" "F.Paste")
			(net "CLK_100M_CPU0_RC_REFCLK1_R_DN")
			(options
				(clearance outline)
				(anchor circle)
			)
			(primitives
				(gr_poly
					(pts
						(xy 0.381 0.1524)
						(arc
							(start -0.2286 0.1524)
							(mid -0.381 0)
							(end -0.2286 -0.1524)
						)
						(xy 0.381 -0.1524)
					)
					(width 0)
					(fill yes)
				)
			)
		)
		(pad "40" smd custom
			(at 4.3688 0.25019 90)
			(size 0.0762 0.0762)
			(layers "F.Cu" "F.Mask" "F.Paste")
			(net "P3V3_DB1200")
			(options
				(clearance outline)
				(anchor circle)
			)
			(primitives
				(gr_poly
					(pts
						(xy 0.381 0.1524)
						(arc
							(start -0.2286 0.1524)
							(mid -0.381 0)
							(end -0.2286 -0.1524)
						)
						(xy 0.381 -0.1524)
					)
					(width 0)
					(fill yes)
				)
			)
		)
		(pad "41" smd custom
			(at 4.3688 -0.249936 90)
			(size 0.0762 0.0762)
			(layers "F.Cu" "F.Mask" "F.Paste")
			(net "GND")
			(options
				(clearance outline)
				(anchor circle)
			)
			(primitives
				(gr_poly
					(pts
						(xy 0.381 0.1524)
						(arc
							(start -0.2286 0.1524)
							(mid -0.381 0)
							(end -0.2286 -0.1524)
						)
						(xy 0.381 -0.1524)
					)
					(width 0)
					(fill yes)
				)
			)
		)
		(pad "42" smd custom
			(at 4.3688 -0.750062 90)
			(size 0.0762 0.0762)
			(layers "F.Cu" "F.Mask" "F.Paste")
			(net "CLK_100M_CPU1_BCLK0_R_DP")
			(options
				(clearance outline)
				(anchor circle)
			)
			(primitives
				(gr_poly
					(pts
						(xy 0.381 0.1524)
						(arc
							(start -0.2286 0.1524)
							(mid -0.381 0)
							(end -0.2286 -0.1524)
						)
						(xy 0.381 -0.1524)
					)
					(width 0)
					(fill yes)
				)
			)
		)
	)
)
